# BASEBOARD_FAB2 (Tioga Pass) — schematic netlist excerpt (pin names and nets, part order shuffled) for the footprints in the layout excerpt that follows; sources: Cadence DE-HDL packaged netlist, KiCad conversion of Wiwynn_Tioga_Pass_MB.brd

R25W64  RES  100.0K 1% CHIP  pkg 0402  page 145 : A = P2E_SSB_BMC_TX_C_DP ; B = GND
C830  CAP  0.22UF 16V 10% X7R  pkg 0402  page 244 : A = P3E_CPU0_PE1_PCH_TXN<15> ; B = P3E_CPU0_PE1_PCH_CON_TXN<15>
R3B3  RES  0.0 5% CHIP  pkg 0402  page 55 : A = SVID_DIO0_CPU1 ; B = SVID_DIO0_CPU1_R

(kicad_pcb
	(version 20260206)
	(generator "pcbnew")
	(generator_version "10.0")
	(general
		(thickness 1.6)
		(legacy_teardrops no)
	)
	(paper "A4")
	(title_block
		(title "Wiwynn_Tioga_Pass_MB.brd")
		(comment 1 "Tioga Pass / footprints 1145-1147 of 4770")
	)
	(layers
		(0 "F.Cu" signal "TOP")
		(4 "In1.Cu" signal "L2GND")
		(6 "In2.Cu" signal "L3")
		(8 "In3.Cu" signal "L4GND")
		(10 "In4.Cu" signal "L5")
		(12 "In5.Cu" signal "L6GND")
		(14 "In6.Cu" signal "L7VCC")
		(16 "In7.Cu" signal "L8VCC")
		(18 "In8.Cu" signal "L9GND")
		(20 "In9.Cu" signal "L10")
		(22 "In10.Cu" signal "L11GND")
		(24 "In11.Cu" signal "L12")
		(26 "In12.Cu" signal "L13GND")
		(2 "B.Cu" signal "BOTTOM")
		(9 "F.Adhes" user "F.Adhesive")
		(11 "B.Adhes" user "B.Adhesive")
		(13 "F.Paste" user "Package Geometry/Pastemask Top")
		(15 "B.Paste" user "Package Geometry/Pastemask Bottom")
		(5 "F.SilkS" user "Ref Des/Silkscreen Top")
		(7 "B.SilkS" user "Ref Des/Silkscreen Bottom")
		(1 "F.Mask" user "Board Geometry/Soldermask Top")
		(3 "B.Mask" user "Board Geometry/Soldermask Bottom")
		(17 "Dwgs.User" user "User.Drawings")
		(19 "Cmts.User" user "User.Comments")
		(21 "Eco1.User" user "User.Eco1")
		(23 "Eco2.User" user "User.Eco2")
		(25 "Edge.Cuts" user "Board Geometry/Outline")
		(27 "Margin" user)
		(31 "F.CrtYd" user "Package Geometry/Place Bound Top")
		(29 "B.CrtYd" user "Package Geometry/Place Bound Bottom")
		(35 "F.Fab" user "Ref Des/Assembly Top")
		(33 "B.Fab" user "Ref Des/Assembly Bottom")
	)
	(footprint ""
		(layer "F.Cu")
		(at 416.511994 -47.828962 180)
		(property "Reference" "R25W64"
			(at -0.8382 -0.67818 180)
			(unlocked yes)
			(layer "F.SilkS")
			(effects
				(font
					(size 0.4064 0.254)
					(thickness 0.1524)
				)
				(justify left)
			)
		)
		(property "Value" ""
			(at 0 0 180)
			(layer "F.Fab")
			(effects
				(font
					(size 1.27 1.27)
				)
			)
		)
		(duplicate_pad_numbers_are_jumpers no)
		(fp_poly
			(pts
				(xy -0.2794 -0.1016) (xy 0.2794 -0.1016) (xy 0.2794 0.9906) (xy -0.2794 0.9906)
			)
			(stroke
				(width 0)
				(type default)
			)
			(fill no)
			(layer "F.CrtYd")
		)
		(fp_line
			(start 0.2794 0.9906)
			(end 0.2794 -0.1016)
			(stroke
				(width 0.1)
				(type default)
			)
			(layer "F.Fab")
		)
		(fp_line
			(start 0.2794 -0.1016)
			(end -0.2794 -0.1016)
			(stroke
				(width 0.1)
				(type default)
			)
			(layer "F.Fab")
		)
		(fp_line
			(start -0.2794 0.9906)
			(end 0.2794 0.9906)
			(stroke
				(width 0.1)
				(type default)
			)
			(layer "F.Fab")
		)
		(fp_line
			(start -0.2794 -0.1016)
			(end -0.2794 0.9906)
			(stroke
				(width 0.1)
				(type default)
			)
			(layer "F.Fab")
		)
		(pad "1" smd rect
			(at 0 0 180)
			(size 0.508 0.508)
			(layers "F.Cu" "F.Mask" "F.Paste")
			(net "P2E_SSB_BMC_TX_C_DP")
		)
		(pad "2" smd rect
			(at 0 0.889 180)
			(size 0.508 0.508)
			(layers "F.Cu" "F.Mask" "F.Paste")
			(net "GND")
		)
		(zone
			(layer "F.Cu")
			(hatch none 0.5)
			(connect_pads
				(clearance 0)
			)
			(min_thickness 0.25)
			(keepout
				(tracks not_allowed)
				(vias allowed)
				(pads allowed)
				(copperpour not_allowed)
				(footprints allowed)
			)
			(placement
				(enabled no)
				(sheetname "")
			)
			(fill
				(thermal_gap 0.5)
				(thermal_bridge_width 0.5)
				(island_removal_mode 0)
			)
			(polygon
				(pts
					(xy 416.765994 -48.463962) (xy 416.257994 -48.463962) (xy 416.257994 -48.082962) (xy 416.765994 -48.082962)
				)
			)
		)
		(zone
			(layer "F.Cu")
			(hatch none 0.5)
			(connect_pads
				(clearance 0)
			)
			(min_thickness 0.25)
			(keepout
				(tracks allowed)
				(vias not_allowed)
				(pads allowed)
				(copperpour not_allowed)
				(footprints allowed)
			)
			(placement
				(enabled no)
				(sheetname "")
			)
			(fill
				(thermal_gap 0.5)
				(thermal_bridge_width 0.5)
				(island_removal_mode 0)
			)
			(polygon
				(pts
					(xy 416.765994 -48.082962) (xy 416.257994 -48.082962) (xy 416.257994 -48.463962) (xy 416.765994 -48.463962)
				)
			)
		)
	)
	(footprint ""
		(layer "F.Cu")
		(at 320.6115 -124.587 -90)
		(property "Reference" "C830"
			(at -0.8382 -0.67818 270)
			(unlocked yes)
			(layer "F.SilkS")
			(effects
				(font
					(size 0.4064 0.254)
					(thickness 0.1524)
				)
				(justify left)
			)
		)
		(property "Value" ""
			(at 0 0 270)
			(layer "F.Fab")
			(effects
				(font
					(size 1.27 1.27)
				)
			)
		)
		(duplicate_pad_numbers_are_jumpers no)
		(fp_poly
			(pts
				(xy 0.3048 -0.1016) (xy 0.3048 0.9906) (xy -0.3048 0.9906) (xy -0.3048 -0.1016)
			)
			(stroke
				(width 0)
				(type default)
			)
			(fill no)
			(layer "F.CrtYd")
		)
		(fp_line
			(start -0.3048 0.9906)
			(end 0.3048 0.9906)
			(stroke
				(width 0.1)
				(type default)
			)
			(layer "F.Fab")
		)
		(fp_line
			(start 0.3048 0.9906)
			(end 0.3048 -0.1016)
			(stroke
				(width 0.1)
				(type default)
			)
			(layer "F.Fab")
		)
		(fp_line
			(start -0.3048 -0.1016)
			(end -0.3048 0.9906)
			(stroke
				(width 0.1)
				(type default)
			)
			(layer "F.Fab")
		)
		(fp_line
			(start 0.3048 -0.1016)
			(end -0.3048 -0.1016)
			(stroke
				(width 0.1)
				(type default)
			)
			(layer "F.Fab")
		)
		(pad "1" smd rect
			(at 0 0 270)
			(size 0.508 0.508)
			(layers "F.Cu" "F.Mask" "F.Paste")
			(net "P3E_CPU0_PE1_PCH_TXN<15>")
		)
		(pad "2" smd rect
			(at 0 0.889 270)
			(size 0.508 0.508)
			(layers "F.Cu" "F.Mask" "F.Paste")
			(net "P3E_CPU0_PE1_PCH_CON_TXN<15>")
		)
		(zone
			(layer "F.Cu")
			(hatch none 0.5)
			(connect_pads
				(clearance 0)
			)
			(min_thickness 0.25)
			(keepout
				(tracks not_allowed)
				(vias allowed)
				(pads allowed)
				(copperpour not_allowed)
				(footprints allowed)
			)
			(placement
				(enabled no)
				(sheetname "")
			)
			(fill
				(thermal_gap 0.5)
				(thermal_bridge_width 0.5)
				(island_removal_mode 0)
			)
			(polygon
				(pts
					(xy 319.9765 -124.841) (xy 319.9765 -124.333) (xy 320.3575 -124.333) (xy 320.3575 -124.841)
				)
			)
		)
		(zone
			(layer "F.Cu")
			(hatch none 0.5)
			(connect_pads
				(clearance 0)
			)
			(min_thickness 0.25)
			(keepout
				(tracks allowed)
				(vias not_allowed)
				(pads allowed)
				(copperpour not_allowed)
				(footprints allowed)
			)
			(placement
				(enabled no)
				(sheetname "")
			)
			(fill
				(thermal_gap 0.5)
				(thermal_bridge_width 0.5)
				(island_removal_mode 0)
			)
			(polygon
				(pts
					(xy 320.3575 -124.841) (xy 320.3575 -124.333) (xy 319.9765 -124.333) (xy 319.9765 -124.841)
				)
			)
		)
	)
	(footprint ""
		(layer "F.Cu")
		(at 155.532836 -119.267986 90)
		(property "Reference" "R3B3"
			(at 0 0 90)
			(layer "F.SilkS")
			(hide yes)
			(effects
				(font
					(size 1.27 1.27)
				)
			)
		)
		(property "Value" ""
			(at 0 0 90)
			(layer "F.Fab")
			(effects
				(font
					(size 1.27 1.27)
				)
			)
		)
		(duplicate_pad_numbers_are_jumpers no)
		(fp_poly
			(pts
				(xy -0.2794 -0.1016) (xy 0.2794 -0.1016) (xy 0.2794 0.9906) (xy -0.2794 0.9906)
			)
			(stroke
				(width 0)
				(type default)
			)
			(fill no)
			(layer "F.CrtYd")
		)
		(fp_line
			(start 0.2794 -0.1016)
			(end -0.2794 -0.1016)
			(stroke
				(width 0.1)
				(type default)
			)
			(layer "F.Fab")
		)
		(fp_line
			(start -0.2794 -0.1016)
			(end -0.2794 0.9906)
			(stroke
				(width 0.1)
				(type default)
			)
			(layer "F.Fab")
		)
		(fp_line
			(start 0.2794 0.9906)
			(end 0.2794 -0.1016)
			(stroke
				(width 0.1)
				(type default)
			)
			(layer "F.Fab")
		)
		(fp_line
			(start -0.2794 0.9906)
			(end 0.2794 0.9906)
			(stroke
				(width 0.1)
				(type default)
			)
			(layer "F.Fab")
		)
		(pad "1" smd rect
			(at 0 0 90)
			(size 0.508 0.508)
			(layers "F.Cu" "F.Mask" "F.Paste")
			(net "SVID_DIO0_CPU1")
		)
		(pad "2" smd rect
			(at 0 0.889 90)
			(size 0.508 0.508)
			(layers "F.Cu" "F.Mask" "F.Paste")
			(net "SVID_DIO0_CPU1_R")
		)
		(zone
			(layer "F.Cu")
			(hatch none 0.5)
			(connect_pads
				(clearance 0)
			)
			(min_thickness 0.25)
			(keepout
				(tracks allowed)
				(vias not_allowed)
				(pads allowed)
				(copperpour not_allowed)
				(footprints allowed)
			)
			(placement
				(enabled no)
				(sheetname "")
			)
			(fill
				(thermal_gap 0.5)
				(thermal_bridge_width 0.5)
				(island_removal_mode 0)
			)
			(polygon
				(pts
					(xy 155.786836 -119.013986) (xy 155.786836 -119.521986) (xy 156.167836 -119.521986) (xy 156.167836 -119.013986)
				)
			)
		)
		(zone
			(layer "F.Cu")
			(hatch none 0.5)
			(connect_pads
				(clearance 0)
			)
			(min_thickness 0.25)
			(keepout
				(tracks not_allowed)
				(vias allowed)
				(pads allowed)
				(copperpour not_allowed)
				(footprints allowed)
			)
			(placement
				(enabled no)
				(sheetname "")
			)
			(fill
				(thermal_gap 0.5)
				(thermal_bridge_width 0.5)
				(island_removal_mode 0)
			)
			(polygon
				(pts
					(xy 156.167836 -119.013986) (xy 156.167836 -119.521986) (xy 155.786836 -119.521986) (xy 155.786836 -119.013986)
				)
			)
		)
	)
)
